(kicad_pcb
	(version 20260206)
	(generator "pcbnew")
	(generator_version "10.0")
	(general
		(thickness 1.6)
		(legacy_teardrops no)
	)
	(paper "A4")
	(title_block
		(title "fcb — 12433-1M.1206WZS1330.brd")
		(comment 1 "Open Vault / Knox (Wiwynn) / footprints 7-12 of 495")
	)
	(layers
		(0 "F.Cu" signal "TOP")
		(4 "In1.Cu" signal "L2GND")
		(6 "In2.Cu" signal "L3VCC")
		(2 "B.Cu" signal "BOTTOM")
		(9 "F.Adhes" user "F.Adhesive")
		(11 "B.Adhes" user "B.Adhesive")
		(13 "F.Paste" user "Package Geometry/Pastemask Top")
		(15 "B.Paste" user "Package Geometry/Pastemask Bottom")
		(5 "F.SilkS" user "Ref Des/Silkscreen Top")
		(7 "B.SilkS" user "Ref Des/Silkscreen Bottom")
		(1 "F.Mask" user "Board Geometry/Soldermask Top")
		(3 "B.Mask" user "Board Geometry/Soldermask Bottom")
		(17 "Dwgs.User" user "User.Drawings")
		(19 "Cmts.User" user "User.Comments")
		(21 "Eco1.User" user "User.Eco1")
		(23 "Eco2.User" user "User.Eco2")
		(25 "Edge.Cuts" user "Board Geometry/Outline")
		(27 "Margin" user)
		(31 "F.CrtYd" user "Package Geometry/Place Bound Top")
		(29 "B.CrtYd" user "Package Geometry/Place Bound Bottom")
		(35 "F.Fab" user "Ref Des/Assembly Top")
		(33 "B.Fab" user "Ref Des/Assembly Bottom")
	)
	(footprint ""
		(layer "F.Cu")
		(at 12.446 -394.081 -90)
		(property "Reference" "TC12"
			(at 0 0 270)
			(layer "F.SilkS")
			(hide yes)
			(effects
				(font
					(size 1.27 1.27)
				)
			)
		)
		(property "Value" "ST15U25VDM-1-GP"
			(at 0 -9.6012 270)
			(unlocked yes)
			(layer "F.Fab")
			(hide yes)
			(effects
				(font
					(size 1.016 1.016)
					(thickness 0.1524)
				)
			)
		)
		(property "Device Type" "CT7343H79"
			(at 0 -11.1252 270)
			(unlocked yes)
			(layer "F.Fab")
			(hide yes)
			(effects
				(font
					(size 1.016 1.016)
					(thickness 0.1524)
				)
			)
		)
		(duplicate_pad_numbers_are_jumpers no)
		(fp_line
			(start -2.286 4.8768)
			(end -2.286 2.032)
			(stroke
				(width 0.1524)
				(type default)
			)
			(layer "F.SilkS")
		)
		(fp_line
			(start 2.286 4.8768)
			(end -2.286 4.8768)
			(stroke
				(width 0.1524)
				(type default)
			)
			(layer "F.SilkS")
		)
		(fp_line
			(start 2.286 2.032)
			(end 2.286 4.8768)
			(stroke
				(width 0.1524)
				(type default)
			)
			(layer "F.SilkS")
		)
		(fp_line
			(start 2.286 -2.032)
			(end 2.286 -4.8768)
			(stroke
				(width 0.1524)
				(type default)
			)
			(layer "F.SilkS")
		)
		(fp_line
			(start 2.1082 -4.699)
			(end -2.1082 -4.699)
			(stroke
				(width 0.508)
				(type default)
			)
			(layer "F.SilkS")
		)
		(fp_line
			(start -2.286 -4.8768)
			(end -2.286 -2.032)
			(stroke
				(width 0.1524)
				(type default)
			)
			(layer "F.SilkS")
		)
		(fp_line
			(start 2.286 -4.8768)
			(end -2.286 -4.8768)
			(stroke
				(width 0.1524)
				(type default)
			)
			(layer "F.SilkS")
		)
		(fp_rect
			(start -2.1463 3.6449)
			(end 2.1463 -3.6449)
			(stroke
				(width 0)
				(type default)
			)
			(fill no)
			(layer "F.CrtYd")
		)
		(fp_poly
			(pts
				(xy -2.54 4.953) (xy -2.54 4.2926) (xy -3.81 4.2926) (xy -3.81 -4.2926) (xy -2.54 -4.2926) (xy -2.54 -4.953)
				(xy 2.54 -4.953) (xy 2.54 -4.2926) (xy 3.81 -4.2926) (xy 3.81 -1.6256) (xy 2.1463 -1.6256) (xy 2.1463 -3.6449)
				(xy -2.1463 -3.6449) (xy -2.1463 3.6449) (xy 2.1463 3.6449) (xy 2.1463 -1.6129) (xy 3.81 -1.6129)
				(xy 3.81 4.2926) (xy 2.54 4.2926) (xy 2.54 4.953)
			)
			(stroke
				(width 0)
				(type default)
			)
			(fill no)
			(layer "F.CrtYd")
		)
		(fp_rect
			(start -2.54 4.953)
			(end 2.54 -4.953)
			(stroke
				(width 0)
				(type default)
			)
			(fill no)
			(layer "F.Fab")
		)
		(fp_rect
			(start -3.81 4.2926)
			(end -2.54 -4.2926)
			(stroke
				(width 0)
				(type default)
			)
			(fill no)
			(layer "F.Fab")
		)
		(fp_rect
			(start 2.54 4.2926)
			(end 3.81 -4.2926)
			(stroke
				(width 0)
				(type default)
			)
			(fill no)
			(layer "F.Fab")
		)
		(pad "1" smd rect
			(at 0 -3.1496 270)
			(size 2.413 2.286)
			(layers "F.Cu" "F.Mask" "F.Paste")
			(net "P12V")
		)
		(pad "2" smd rect
			(at 0 3.1496 270)
			(size 2.413 2.286)
			(layers "F.Cu" "F.Mask" "F.Paste")
			(net "GND")
		)
		(zone
			(layer "F.Cu")
			(hatch none 0.5)
			(connect_pads
				(clearance 0)
			)
			(min_thickness 0.25)
			(keepout
				(tracks allowed)
				(vias not_allowed)
				(pads allowed)
				(copperpour not_allowed)
				(footprints allowed)
			)
			(placement
				(enabled no)
				(sheetname "")
			)
			(fill
				(thermal_gap 0.5)
				(thermal_bridge_width 0.5)
				(island_removal_mode 0)
			)
			(polygon
				(pts
					(xy 7.8486 -395.5923) (xy 7.8486 -392.5697) (xy 10.7442 -392.5697) (xy 11.0744 -392.5697) (xy 11.0744 -395.5923)
					(xy 10.7442 -395.5923)
				)
			)
		)
		(zone
			(layer "F.Cu")
			(hatch none 0.5)
			(connect_pads
				(clearance 0)
			)
			(min_thickness 0.25)
			(keepout
				(tracks allowed)
				(vias not_allowed)
				(pads allowed)
				(copperpour not_allowed)
				(footprints allowed)
			)
			(placement
				(enabled no)
				(sheetname "")
			)
			(fill
				(thermal_gap 0.5)
				(thermal_bridge_width 0.5)
				(island_removal_mode 0)
			)
			(polygon
				(pts
					(xy 14.1351 -392.5697) (xy 17.0434 -392.5697) (xy 17.0434 -395.5923) (xy 14.1478 -395.5923) (xy 13.8176 -395.5923)
					(xy 13.8176 -392.5697)
				)
			)
		)
	)
	(footprint ""
		(layer "F.Cu")
		(at 24.70531 -151.325834)
		(property "Reference" "R10"
			(at 0 0 0)
			(layer "F.SilkS")
			(hide yes)
			(effects
				(font
					(size 1.27 1.27)
				)
			)
		)
		(property "Value" "1MR2J-1-GP"
			(at 0.064008 -3.993896 0)
			(unlocked yes)
			(layer "F.Fab")
			(hide yes)
			(effects
				(font
					(size 1.016 1.016)
					(thickness 0.1524)
				)
			)
		)
		(property "Device Type" "R402H16"
			(at 0.064008 -5.517896 0)
			(unlocked yes)
			(layer "F.Fab")
			(hide yes)
			(effects
				(font
					(size 1.016 1.016)
					(thickness 0.1524)
				)
			)
		)
		(duplicate_pad_numbers_are_jumpers no)
		(fp_line
			(start -0.508 -0.9398)
			(end -0.508 0.9398)
			(stroke
				(width 0.1524)
				(type default)
			)
			(layer "F.SilkS")
		)
		(fp_line
			(start 0.508 -0.9398)
			(end -0.508 -0.9398)
			(stroke
				(width 0.1524)
				(type default)
			)
			(layer "F.SilkS")
		)
		(fp_rect
			(start -0.508 0.9398)
			(end 0.508 -0.9398)
			(stroke
				(width 0)
				(type default)
			)
			(fill no)
			(layer "F.CrtYd")
		)
		(fp_rect
			(start -0.508 0.9398)
			(end 0.508 -0.9398)
			(stroke
				(width 0)
				(type default)
			)
			(fill no)
			(layer "F.Fab")
		)
		(pad "1" smd custom
			(at 0 -0.4445)
			(size 0.1397 0.1397)
			(layers "F.Cu" "F.Mask" "F.Paste")
			(net "NCT7904_CASEOPEN")
			(options
				(clearance outline)
				(anchor circle)
			)
			(primitives
				(gr_poly
					(pts
						(arc
							(start -0.1778 -0.2794)
							(mid -0.249642 -0.249642)
							(end -0.2794 -0.1778)
						)
						(arc
							(start -0.2794 0.1778)
							(mid -0.249642 0.249642)
							(end -0.1778 0.2794)
						)
						(arc
							(start 0.1778 0.2794)
							(mid 0.249642 0.249642)
							(end 0.2794 0.1778)
						)
						(arc
							(start 0.2794 -0.1778)
							(mid 0.249642 -0.249642)
							(end 0.1778 -0.2794)
						)
					)
					(width 0)
					(fill yes)
				)
			)
		)
		(pad "2" smd custom
			(at 0 0.4445)
			(size 0.1397 0.1397)
			(layers "F.Cu" "F.Mask" "F.Paste")
			(net "NCT7904_3VSB")
			(options
				(clearance outline)
				(anchor circle)
			)
			(primitives
				(gr_poly
					(pts
						(arc
							(start -0.1778 -0.2794)
							(mid -0.249642 -0.249642)
							(end -0.2794 -0.1778)
						)
						(arc
							(start -0.2794 0.1778)
							(mid -0.249642 0.249642)
							(end -0.1778 0.2794)
						)
						(arc
							(start 0.1778 0.2794)
							(mid 0.249642 0.249642)
							(end 0.2794 0.1778)
						)
						(arc
							(start 0.2794 -0.1778)
							(mid 0.249642 -0.249642)
							(end 0.1778 -0.2794)
						)
					)
					(width 0)
					(fill yes)
				)
			)
		)
	)
	(footprint ""
		(layer "F.Cu")
		(at 14.8844 -47.5742 -90)
		(property "Reference" "R185"
			(at 0 0 270)
			(layer "F.SilkS")
			(hide yes)
			(effects
				(font
					(size 1.27 1.27)
				)
			)
		)
		(property "Value" "0R2J-2-GP"
			(at 0.064008 -3.993896 270)
			(unlocked yes)
			(layer "F.Fab")
			(hide yes)
			(effects
				(font
					(size 1.016 1.016)
					(thickness 0.1524)
				)
			)
		)
		(property "Device Type" "R402H16"
			(at 0.064008 -5.517896 270)
			(unlocked yes)
			(layer "F.Fab")
			(hide yes)
			(effects
				(font
					(size 1.016 1.016)
					(thickness 0.1524)
				)
			)
		)
		(duplicate_pad_numbers_are_jumpers no)
		(fp_line
			(start -0.508 -0.9398)
			(end -0.508 0.9398)
			(stroke
				(width 0.1524)
				(type default)
			)
			(layer "F.SilkS")
		)
		(fp_line
			(start 0.508 -0.9398)
			(end -0.508 -0.9398)
			(stroke
				(width 0.1524)
				(type default)
			)
			(layer "F.SilkS")
		)
		(fp_rect
			(start -0.508 0.9398)
			(end 0.508 -0.9398)
			(stroke
				(width 0)
				(type default)
			)
			(fill no)
			(layer "F.CrtYd")
		)
		(fp_rect
			(start -0.508 0.9398)
			(end 0.508 -0.9398)
			(stroke
				(width 0)
				(type default)
			)
			(fill no)
			(layer "F.Fab")
		)
		(pad "1" smd custom
			(at 0 -0.4445 270)
			(size 0.1397 0.1397)
			(layers "F.Cu" "F.Mask" "F.Paste")
			(net "SD_LATCH_RELEASE_L")
			(options
				(clearance outline)
				(anchor circle)
			)
			(primitives
				(gr_poly
					(pts
						(arc
							(start -0.1778 -0.2794)
							(mid -0.249642 -0.249642)
							(end -0.2794 -0.1778)
						)
						(arc
							(start -0.2794 0.1778)
							(mid -0.249642 0.249642)
							(end -0.1778 0.2794)
						)
						(arc
							(start 0.1778 0.2794)
							(mid 0.249642 0.249642)
							(end 0.2794 0.1778)
						)
						(arc
							(start 0.2794 -0.1778)
							(mid 0.249642 -0.249642)
							(end 0.1778 -0.2794)
						)
					)
					(width 0)
					(fill yes)
				)
			)
		)
		(pad "2" smd custom
			(at 0 0.4445 270)
			(size 0.1397 0.1397)
			(layers "F.Cu" "F.Mask" "F.Paste")
			(net "D_LATCH_PRE#")
			(options
				(clearance outline)
				(anchor circle)
			)
			(primitives
				(gr_poly
					(pts
						(arc
							(start -0.1778 -0.2794)
							(mid -0.249642 -0.249642)
							(end -0.2794 -0.1778)
						)
						(arc
							(start -0.2794 0.1778)
							(mid -0.249642 0.249642)
							(end -0.1778 0.2794)
						)
						(arc
							(start 0.1778 0.2794)
							(mid 0.249642 0.249642)
							(end 0.2794 0.1778)
						)
						(arc
							(start 0.2794 -0.1778)
							(mid 0.249642 -0.249642)
							(end 0.1778 -0.2794)
						)
					)
					(width 0)
					(fill yes)
				)
			)
		)
	)
	(footprint ""
		(layer "F.Cu")
		(at 38.989 -144.3482 180)
		(property "Reference" "PR113"
			(at 0 0 180)
			(layer "F.SilkS")
			(hide yes)
			(effects
				(font
					(size 1.27 1.27)
				)
			)
		)
		(property "Value" "6K81R2F-1-GP"
			(at 0.064008 -3.993896 180)
			(unlocked yes)
			(layer "F.Fab")
			(hide yes)
			(effects
				(font
					(size 1.016 1.016)
					(thickness 0.1524)
				)
			)
		)
		(property "Device Type" "R402H16"
			(at 0.064008 -5.517896 180)
			(unlocked yes)
			(layer "F.Fab")
			(hide yes)
			(effects
				(font
					(size 1.016 1.016)
					(thickness 0.1524)
				)
			)
		)
		(duplicate_pad_numbers_are_jumpers no)
		(fp_line
			(start 0.508 -0.9398)
			(end -0.508 -0.9398)
			(stroke
				(width 0.1524)
				(type default)
			)
			(layer "F.SilkS")
		)
		(fp_line
			(start -0.508 -0.9398)
			(end -0.508 0.9398)
			(stroke
				(width 0.1524)
				(type default)
			)
			(layer "F.SilkS")
		)
		(fp_rect
			(start -0.508 0.9398)
			(end 0.508 -0.9398)
			(stroke
				(width 0)
				(type default)
			)
			(fill no)
			(layer "F.CrtYd")
		)
		(fp_rect
			(start -0.508 0.9398)
			(end 0.508 -0.9398)
			(stroke
				(width 0)
				(type default)
			)
			(fill no)
			(layer "F.Fab")
		)
		(pad "1" smd custom
			(at 0 -0.4445 180)
			(size 0.1397 0.1397)
			(layers "F.Cu" "F.Mask" "F.Paste")
			(net "P12VL_2490_EN_2")
			(options
				(clearance outline)
				(anchor circle)
			)
			(primitives
				(gr_poly
					(pts
						(arc
							(start -0.1778 -0.2794)
							(mid -0.249642 -0.249642)
							(end -0.2794 -0.1778)
						)
						(arc
							(start -0.2794 0.1778)
							(mid -0.249642 0.249642)
							(end -0.1778 0.2794)
						)
						(arc
							(start 0.1778 0.2794)
							(mid 0.249642 0.249642)
							(end 0.2794 0.1778)
						)
						(arc
							(start 0.2794 -0.1778)
							(mid 0.249642 -0.249642)
							(end 0.1778 -0.2794)
						)
					)
					(width 0)
					(fill yes)
				)
			)
		)
		(pad "2" smd custom
			(at 0 0.4445 180)
			(size 0.1397 0.1397)
			(layers "F.Cu" "F.Mask" "F.Paste")
			(net "GND")
			(options
				(clearance outline)
				(anchor circle)
			)
			(primitives
				(gr_poly
					(pts
						(arc
							(start -0.1778 -0.2794)
							(mid -0.249642 -0.249642)
							(end -0.2794 -0.1778)
						)
						(arc
							(start -0.2794 0.1778)
							(mid -0.249642 0.249642)
							(end -0.1778 0.2794)
						)
						(arc
							(start 0.1778 0.2794)
							(mid 0.249642 0.249642)
							(end 0.2794 0.1778)
						)
						(arc
							(start 0.2794 -0.1778)
							(mid 0.249642 -0.249642)
							(end 0.1778 -0.2794)
						)
					)
					(width 0)
					(fill yes)
				)
			)
		)
	)
	(footprint ""
		(layer "F.Cu")
		(at 33.782 -381 180)
		(property "Reference" "PR23"
			(at 0 0 180)
			(layer "F.SilkS")
			(hide yes)
			(effects
				(font
					(size 1.27 1.27)
				)
			)
		)
		(property "Value" "10R2F-L-GP"
			(at 0.064008 -3.993896 180)
			(unlocked yes)
			(layer "F.Fab")
			(hide yes)
			(effects
				(font
					(size 1.016 1.016)
					(thickness 0.1524)
				)
			)
		)
		(property "Device Type" "R402H14"
			(at 0.064008 -5.517896 180)
			(unlocked yes)
			(layer "F.Fab")
			(hide yes)
			(effects
				(font
					(size 1.016 1.016)
					(thickness 0.1524)
				)
			)
		)
		(duplicate_pad_numbers_are_jumpers no)
		(fp_line
			(start 0.508 -0.9398)
			(end -0.508 -0.9398)
			(stroke
				(width 0.1524)
				(type default)
			)
			(layer "F.SilkS")
		)
		(fp_line
			(start -0.508 -0.9398)
			(end -0.508 0.9398)
			(stroke
				(width 0.1524)
				(type default)
			)
			(layer "F.SilkS")
		)
		(fp_rect
			(start -0.508 0.9398)
			(end 0.508 -0.9398)
			(stroke
				(width 0)
				(type default)
			)
			(fill no)
			(layer "F.CrtYd")
		)
		(fp_rect
			(start -0.508 0.9398)
			(end 0.508 -0.9398)
			(stroke
				(width 0)
				(type default)
			)
			(fill no)
			(layer "F.Fab")
		)
		(pad "1" smd custom
			(at 0 -0.4445 180)
			(size 0.1397 0.1397)
			(layers "F.Cu" "F.Mask" "F.Paste")
			(net "ADM1276_SENSE-")
			(options
				(clearance outline)
				(anchor circle)
			)
			(primitives
				(gr_poly
					(pts
						(arc
							(start -0.1778 -0.2794)
							(mid -0.249642 -0.249642)
							(end -0.2794 -0.1778)
						)
						(arc
							(start -0.2794 0.1778)
							(mid -0.249642 0.249642)
							(end -0.1778 0.2794)
						)
						(arc
							(start 0.1778 0.2794)
							(mid 0.249642 0.249642)
							(end 0.2794 0.1778)
						)
						(arc
							(start 0.2794 -0.1778)
							(mid 0.249642 -0.249642)
							(end 0.1778 -0.2794)
						)
					)
					(width 0)
					(fill yes)
				)
			)
		)
		(pad "2" smd custom
			(at 0 0.4445 180)
			(size 0.1397 0.1397)
			(layers "F.Cu" "F.Mask" "F.Paste")
			(net "SENSE-_R3")
			(options
				(clearance outline)
				(anchor circle)
			)
			(primitives
				(gr_poly
					(pts
						(arc
							(start -0.1778 -0.2794)
							(mid -0.249642 -0.249642)
							(end -0.2794 -0.1778)
						)
						(arc
							(start -0.2794 0.1778)
							(mid -0.249642 0.249642)
							(end -0.1778 0.2794)
						)
						(arc
							(start 0.1778 0.2794)
							(mid 0.249642 0.249642)
							(end 0.2794 0.1778)
						)
						(arc
							(start 0.2794 -0.1778)
							(mid 0.249642 -0.249642)
							(end 0.1778 -0.2794)
						)
					)
					(width 0)
					(fill yes)
				)
			)
		)
	)
	(footprint ""
		(layer "F.Cu")
		(at 32.766 -374.777 180)
		(property "Reference" "PR10"
			(at 0 0 180)
			(layer "F.SilkS")
			(hide yes)
			(effects
				(font
					(size 1.27 1.27)
				)
			)
		)
		(property "Value" "0R0402-PAD-2-GP"
			(at 0 -2.8702 180)
			(unlocked yes)
			(layer "F.Fab")
			(hide yes)
			(effects
				(font
					(size 1.016 1.016)
					(thickness 0.1524)
				)
			)
		)
		(property "Device Type" "0R0402-PAD-1"
			(at 0 -4.3942 180)
			(unlocked yes)
			(layer "F.Fab")
			(hide yes)
			(effects
				(font
					(size 1.016 1.016)
					(thickness 0.1524)
				)
			)
		)
		(duplicate_pad_numbers_are_jumpers no)
		(fp_line
			(start 0.508 -0.9398)
			(end -0.508 -0.9398)
			(stroke
				(width 0.1524)
				(type default)
			)
			(layer "F.SilkS")
		)
		(fp_line
			(start -0.508 -0.9398)
			(end -0.508 0.9398)
			(stroke
				(width 0.1524)
				(type default)
			)
			(layer "F.SilkS")
		)
		(fp_rect
			(start -0.508 0.9398)
			(end 0.508 -0.9398)
			(stroke
				(width 0)
				(type default)
			)
			(fill no)
			(layer "F.CrtYd")
		)
		(fp_rect
			(start -0.508 0.9398)
			(end 0.508 -0.9398)
			(stroke
				(width 0)
				(type default)
			)
			(fill no)
			(layer "F.Fab")
		)
		(pad "1" smd custom
			(at 0 -0.4445 180)
			(size 0.1397 0.1397)
			(layers "F.Cu" "F.Mask" "F.Paste")
			(net "ADM1276_GATE_DRV")
			(options
				(clearance outline)
				(anchor circle)
			)
			(primitives
				(gr_poly
					(pts
						(xy -0.2794 0.3683)
						(arc
							(start -0.2794 -0.2667)
							(mid -0.249642 -0.338542)
							(end -0.1778 -0.3683)
						)
						(arc
							(start 0.1778 -0.3683)
							(mid 0.249642 -0.338542)
							(end 0.2794 -0.2667)
						)
						(xy 0.2794 0.3683)
					)
					(width 0)
					(fill yes)
				)
			)
		)
		(pad "2" smd custom
			(at 0 0.4445 180)
			(size 0.1397 0.1397)
			(layers "F.Cu" "F.Mask" "F.Paste")
			(net "ADM1276_GATE")
			(options
				(clearance outline)
				(anchor circle)
			)
			(primitives
				(gr_poly
					(pts
						(arc
							(start -0.1778 0.3683)
							(mid -0.249642 0.338542)
							(end -0.2794 0.2667)
						)
						(xy -0.2794 -0.3683) (xy 0.2794 -0.3683)
						(arc
							(start 0.2794 0.2667)
							(mid 0.249642 0.338542)
							(end 0.1778 0.3683)
						)
					)
					(width 0)
					(fill yes)
				)
			)
		)
	)
)
